(kicad_pcb
	(version 20260206)
	(generator "pcbnew")
	(generator_version "10.0")
	(general
		(thickness 1.6)
		(legacy_teardrops no)
	)
	(paper "A4")
	(title_block
		(title "pdpb — Lightning_PDPB_BRD.brd")
		(comment 1 "Lightning (Wiwynn / Facebook NVMe JBOF) / footprints 21-27 of 1140")
	)
	(layers
		(0 "F.Cu" signal "TOP")
		(4 "In1.Cu" signal "L2GND")
		(6 "In2.Cu" signal "L3")
		(8 "In3.Cu" signal "L4VCC")
		(10 "In4.Cu" signal "L5VCC")
		(12 "In5.Cu" signal "L6")
		(14 "In6.Cu" signal "L7GND")
		(2 "B.Cu" signal "BOTTOM")
		(9 "F.Adhes" user "F.Adhesive")
		(11 "B.Adhes" user "B.Adhesive")
		(13 "F.Paste" user "Package Geometry/Pastemask Top")
		(15 "B.Paste" user "Package Geometry/Pastemask Bottom")
		(5 "F.SilkS" user "Ref Des/Silkscreen Top")
		(7 "B.SilkS" user "Ref Des/Silkscreen Bottom")
		(1 "F.Mask" user "Board Geometry/Soldermask Top")
		(3 "B.Mask" user "Board Geometry/Soldermask Bottom")
		(17 "Dwgs.User" user "User.Drawings")
		(19 "Cmts.User" user "User.Comments")
		(21 "Eco1.User" user "User.Eco1")
		(23 "Eco2.User" user "User.Eco2")
		(25 "Edge.Cuts" user "Board Geometry/Outline")
		(27 "Margin" user)
		(31 "F.CrtYd" user "Package Geometry/Place Bound Top")
		(29 "B.CrtYd" user "Package Geometry/Place Bound Bottom")
		(35 "F.Fab" user "Ref Des/Assembly Top")
		(33 "B.Fab" user "Ref Des/Assembly Bottom")
	)
	(footprint ""
		(layer "F.Cu")
		(at 30.3022 -17.145 180)
		(property "Reference" "R418"
			(at 0 0 180)
			(layer "F.SilkS")
			(hide yes)
			(effects
				(font
					(size 1.27 1.27)
				)
			)
		)
		(property "Value" "0R2J-2-GP"
			(at 0.064008 -3.993896 180)
			(unlocked yes)
			(layer "F.Fab")
			(hide yes)
			(effects
				(font
					(size 1.016 1.016)
					(thickness 0.1524)
				)
			)
		)
		(property "Device Type" "R402H16"
			(at 0.064008 -5.517896 180)
			(unlocked yes)
			(layer "F.Fab")
			(hide yes)
			(effects
				(font
					(size 1.016 1.016)
					(thickness 0.1524)
				)
			)
		)
		(duplicate_pad_numbers_are_jumpers no)
		(fp_line
			(start 0.508 -0.9398)
			(end -0.508 -0.9398)
			(stroke
				(width 0.1524)
				(type default)
			)
			(layer "F.SilkS")
		)
		(fp_line
			(start -0.508 -0.9398)
			(end -0.508 0.9398)
			(stroke
				(width 0.1524)
				(type default)
			)
			(layer "F.SilkS")
		)
		(fp_rect
			(start -0.508 0.9398)
			(end 0.508 -0.9398)
			(stroke
				(width 0)
				(type default)
			)
			(fill no)
			(layer "F.CrtYd")
		)
		(fp_rect
			(start -0.508 0.9398)
			(end 0.508 -0.9398)
			(stroke
				(width 0)
				(type default)
			)
			(fill no)
			(layer "F.Fab")
		)
		(pad "1" smd custom
			(at 0 -0.4445 180)
			(size 0.1397 0.1397)
			(layers "F.Cu" "F.Mask" "F.Paste")
			(net "SDA_DR14_R")
			(options
				(clearance outline)
				(anchor circle)
			)
			(primitives
				(gr_poly
					(pts
						(arc
							(start -0.1778 -0.2794)
							(mid -0.249642 -0.249642)
							(end -0.2794 -0.1778)
						)
						(arc
							(start -0.2794 0.1778)
							(mid -0.249642 0.249642)
							(end -0.1778 0.2794)
						)
						(arc
							(start 0.1778 0.2794)
							(mid 0.249642 0.249642)
							(end 0.2794 0.1778)
						)
						(arc
							(start 0.2794 -0.1778)
							(mid 0.249642 -0.249642)
							(end 0.1778 -0.2794)
						)
					)
					(width 0)
					(fill yes)
				)
			)
		)
		(pad "2" smd custom
			(at 0 0.4445 180)
			(size 0.1397 0.1397)
			(layers "F.Cu" "F.Mask" "F.Paste")
			(net "SDA_DR14")
			(options
				(clearance outline)
				(anchor circle)
			)
			(primitives
				(gr_poly
					(pts
						(arc
							(start -0.1778 -0.2794)
							(mid -0.249642 -0.249642)
							(end -0.2794 -0.1778)
						)
						(arc
							(start -0.2794 0.1778)
							(mid -0.249642 0.249642)
							(end -0.1778 0.2794)
						)
						(arc
							(start 0.1778 0.2794)
							(mid 0.249642 0.249642)
							(end 0.2794 0.1778)
						)
						(arc
							(start 0.2794 -0.1778)
							(mid 0.249642 -0.249642)
							(end 0.1778 -0.2794)
						)
					)
					(width 0)
					(fill yes)
				)
			)
		)
	)
	(footprint ""
		(layer "F.Cu")
		(at 25.4 -339.852 180)
		(property "Reference" "PC1224"
			(at 0 0 180)
			(layer "F.SilkS")
			(hide yes)
			(effects
				(font
					(size 1.27 1.27)
				)
			)
		)
		(property "Value" "SCD1U25V3KX-GP"
			(at 0 -2.8194 180)
			(unlocked yes)
			(layer "F.Fab")
			(hide yes)
			(effects
				(font
					(size 1.016 1.016)
					(thickness 0.1524)
				)
			)
		)
		(property "Device Type" "C603H36"
			(at 0 -4.3434 180)
			(unlocked yes)
			(layer "F.Fab")
			(hide yes)
			(effects
				(font
					(size 1.016 1.016)
					(thickness 0.1524)
				)
			)
		)
		(duplicate_pad_numbers_are_jumpers no)
		(fp_line
			(start 0.508 0)
			(end -0.508 0)
			(stroke
				(width 0.2032)
				(type default)
			)
			(layer "F.SilkS")
		)
		(fp_rect
			(start -0.5842 1.3335)
			(end 0.5842 -1.3335)
			(stroke
				(width 0)
				(type default)
			)
			(fill no)
			(layer "F.CrtYd")
		)
		(fp_rect
			(start -0.5842 1.3335)
			(end 0.5842 -1.3335)
			(stroke
				(width 0)
				(type default)
			)
			(fill no)
			(layer "F.Fab")
		)
		(pad "1" smd custom
			(at 0 -0.762 180)
			(size 0.2159 0.2159)
			(layers "F.Cu" "F.Mask" "F.Paste")
			(net "P3V3")
			(options
				(clearance outline)
				(anchor circle)
			)
			(primitives
				(gr_poly
					(pts
						(arc
							(start -0.3302 -0.4318)
							(mid -0.402042 -0.402042)
							(end -0.4318 -0.3302)
						)
						(arc
							(start -0.4318 0.3302)
							(mid -0.402042 0.402042)
							(end -0.3302 0.4318)
						)
						(arc
							(start 0.3302 0.4318)
							(mid 0.402042 0.402042)
							(end 0.4318 0.3302)
						)
						(arc
							(start 0.4318 -0.3302)
							(mid 0.402042 -0.402042)
							(end 0.3302 -0.4318)
						)
					)
					(width 0)
					(fill yes)
				)
			)
		)
		(pad "2" smd custom
			(at 0 0.762 180)
			(size 0.2159 0.2159)
			(layers "F.Cu" "F.Mask" "F.Paste")
			(net "GND")
			(options
				(clearance outline)
				(anchor circle)
			)
			(primitives
				(gr_poly
					(pts
						(arc
							(start -0.3302 -0.4318)
							(mid -0.402042 -0.402042)
							(end -0.4318 -0.3302)
						)
						(arc
							(start -0.4318 0.3302)
							(mid -0.402042 0.402042)
							(end -0.3302 0.4318)
						)
						(arc
							(start 0.3302 0.4318)
							(mid 0.402042 0.402042)
							(end 0.4318 0.3302)
						)
						(arc
							(start 0.4318 -0.3302)
							(mid 0.402042 -0.402042)
							(end 0.3302 -0.4318)
						)
					)
					(width 0)
					(fill yes)
				)
			)
		)
	)
	(footprint ""
		(layer "F.Cu")
		(at 68.707 -437.388 90)
		(property "Reference" "R368"
			(at 0 0 90)
			(layer "F.SilkS")
			(hide yes)
			(effects
				(font
					(size 1.27 1.27)
				)
			)
		)
		(property "Value" "4K7R2J-2-GP"
			(at 0.064008 -3.993896 90)
			(unlocked yes)
			(layer "F.Fab")
			(hide yes)
			(effects
				(font
					(size 1.016 1.016)
					(thickness 0.1524)
				)
			)
		)
		(property "Device Type" "R402H16"
			(at 0.064008 -5.517896 90)
			(unlocked yes)
			(layer "F.Fab")
			(hide yes)
			(effects
				(font
					(size 1.016 1.016)
					(thickness 0.1524)
				)
			)
		)
		(duplicate_pad_numbers_are_jumpers no)
		(fp_line
			(start 0.508 -0.9398)
			(end -0.508 -0.9398)
			(stroke
				(width 0.1524)
				(type default)
			)
			(layer "F.SilkS")
		)
		(fp_line
			(start -0.508 -0.9398)
			(end -0.508 0.9398)
			(stroke
				(width 0.1524)
				(type default)
			)
			(layer "F.SilkS")
		)
		(fp_rect
			(start -0.508 0.9398)
			(end 0.508 -0.9398)
			(stroke
				(width 0)
				(type default)
			)
			(fill no)
			(layer "F.CrtYd")
		)
		(fp_rect
			(start -0.508 0.9398)
			(end 0.508 -0.9398)
			(stroke
				(width 0)
				(type default)
			)
			(fill no)
			(layer "F.Fab")
		)
		(pad "1" smd custom
			(at 0 -0.4445 90)
			(size 0.1397 0.1397)
			(layers "F.Cu" "F.Mask" "F.Paste")
			(net "P3V3")
			(options
				(clearance outline)
				(anchor circle)
			)
			(primitives
				(gr_poly
					(pts
						(arc
							(start -0.1778 -0.2794)
							(mid -0.249642 -0.249642)
							(end -0.2794 -0.1778)
						)
						(arc
							(start -0.2794 0.1778)
							(mid -0.249642 0.249642)
							(end -0.1778 0.2794)
						)
						(arc
							(start 0.1778 0.2794)
							(mid 0.249642 0.249642)
							(end 0.2794 0.1778)
						)
						(arc
							(start 0.2794 -0.1778)
							(mid 0.249642 -0.249642)
							(end 0.1778 -0.2794)
						)
					)
					(width 0)
					(fill yes)
				)
			)
		)
		(pad "2" smd custom
			(at 0 0.4445 90)
			(size 0.1397 0.1397)
			(layers "F.Cu" "F.Mask" "F.Paste")
			(net "I2C_B_SDA")
			(options
				(clearance outline)
				(anchor circle)
			)
			(primitives
				(gr_poly
					(pts
						(arc
							(start -0.1778 -0.2794)
							(mid -0.249642 -0.249642)
							(end -0.2794 -0.1778)
						)
						(arc
							(start -0.2794 0.1778)
							(mid -0.249642 0.249642)
							(end -0.1778 0.2794)
						)
						(arc
							(start 0.1778 0.2794)
							(mid 0.249642 0.249642)
							(end 0.2794 0.1778)
						)
						(arc
							(start 0.2794 -0.1778)
							(mid 0.249642 -0.249642)
							(end 0.1778 -0.2794)
						)
					)
					(width 0)
					(fill yes)
				)
			)
		)
	)
	(footprint ""
		(layer "F.Cu")
		(at 100.4824 -304.927 180)
		(property "Reference" "C9515"
			(at 0 0 180)
			(layer "F.SilkS")
			(hide yes)
			(effects
				(font
					(size 1.27 1.27)
				)
			)
		)
		(property "Value" "SCD1U16V2KX-3GP"
			(at 1.1811 -2.7051 180)
			(unlocked yes)
			(layer "F.Fab")
			(hide yes)
			(effects
				(font
					(size 1.016 1.016)
					(thickness 0.1524)
				)
			)
		)
		(property "Device Type" "C402H22"
			(at 1.1811 -4.2291 180)
			(unlocked yes)
			(layer "F.Fab")
			(hide yes)
			(effects
				(font
					(size 1.016 1.016)
					(thickness 0.1524)
				)
			)
		)
		(duplicate_pad_numbers_are_jumpers no)
		(fp_rect
			(start -0.4318 0.9525)
			(end 0.4318 -0.9525)
			(stroke
				(width 0)
				(type default)
			)
			(fill no)
			(layer "F.CrtYd")
		)
		(fp_rect
			(start -0.4318 0.9525)
			(end 0.4318 -0.9525)
			(stroke
				(width 0)
				(type default)
			)
			(fill no)
			(layer "F.Fab")
		)
		(pad "1" smd custom
			(at 0 -0.4445 180)
			(size 0.1524 0.1524)
			(layers "F.Cu" "F.Mask" "F.Paste")
			(net "VDD_DIFF_2")
			(options
				(clearance outline)
				(anchor circle)
			)
			(primitives
				(gr_poly
					(pts
						(arc
							(start 0.3048 -0.2032)
							(mid 0.275042 -0.275042)
							(end 0.2032 -0.3048)
						)
						(arc
							(start -0.2032 -0.3048)
							(mid -0.275042 -0.275042)
							(end -0.3048 -0.2032)
						)
						(arc
							(start -0.3048 0.2032)
							(mid -0.275042 0.275042)
							(end -0.2032 0.3048)
						)
						(arc
							(start 0.2032 0.3048)
							(mid 0.275042 0.275042)
							(end 0.3048 0.2032)
						)
					)
					(width 0)
					(fill yes)
				)
			)
		)
		(pad "2" smd custom
			(at 0 0.4445 180)
			(size 0.1524 0.1524)
			(layers "F.Cu" "F.Mask" "F.Paste")
			(net "GND")
			(options
				(clearance outline)
				(anchor circle)
			)
			(primitives
				(gr_poly
					(pts
						(arc
							(start 0.3048 -0.2032)
							(mid 0.275042 -0.275042)
							(end 0.2032 -0.3048)
						)
						(arc
							(start -0.2032 -0.3048)
							(mid -0.275042 -0.275042)
							(end -0.3048 -0.2032)
						)
						(arc
							(start -0.3048 0.2032)
							(mid -0.275042 0.275042)
							(end -0.2032 0.3048)
						)
						(arc
							(start 0.2032 0.3048)
							(mid 0.275042 0.275042)
							(end 0.3048 0.2032)
						)
					)
					(width 0)
					(fill yes)
				)
			)
		)
	)
	(footprint ""
		(layer "F.Cu")
		(at 36.576 -268.351 180)
		(property "Reference" "PC1249"
			(at 0 0 180)
			(layer "F.SilkS")
			(hide yes)
			(effects
				(font
					(size 1.27 1.27)
				)
			)
		)
		(property "Value" "SCD1U25V3KX-GP"
			(at 0 -2.8194 180)
			(unlocked yes)
			(layer "F.Fab")
			(hide yes)
			(effects
				(font
					(size 1.016 1.016)
					(thickness 0.1524)
				)
			)
		)
		(property "Device Type" "C603H36"
			(at 0 -4.3434 180)
			(unlocked yes)
			(layer "F.Fab")
			(hide yes)
			(effects
				(font
					(size 1.016 1.016)
					(thickness 0.1524)
				)
			)
		)
		(duplicate_pad_numbers_are_jumpers no)
		(fp_line
			(start 0.508 0)
			(end -0.508 0)
			(stroke
				(width 0.2032)
				(type default)
			)
			(layer "F.SilkS")
		)
		(fp_rect
			(start -0.5842 1.3335)
			(end 0.5842 -1.3335)
			(stroke
				(width 0)
				(type default)
			)
			(fill no)
			(layer "F.CrtYd")
		)
		(fp_rect
			(start -0.5842 1.3335)
			(end 0.5842 -1.3335)
			(stroke
				(width 0)
				(type default)
			)
			(fill no)
			(layer "F.Fab")
		)
		(pad "1" smd custom
			(at 0 -0.762 180)
			(size 0.2159 0.2159)
			(layers "F.Cu" "F.Mask" "F.Paste")
			(net "P3V3")
			(options
				(clearance outline)
				(anchor circle)
			)
			(primitives
				(gr_poly
					(pts
						(arc
							(start -0.3302 -0.4318)
							(mid -0.402042 -0.402042)
							(end -0.4318 -0.3302)
						)
						(arc
							(start -0.4318 0.3302)
							(mid -0.402042 0.402042)
							(end -0.3302 0.4318)
						)
						(arc
							(start 0.3302 0.4318)
							(mid 0.402042 0.402042)
							(end 0.4318 0.3302)
						)
						(arc
							(start 0.4318 -0.3302)
							(mid 0.402042 -0.402042)
							(end 0.3302 -0.4318)
						)
					)
					(width 0)
					(fill yes)
				)
			)
		)
		(pad "2" smd custom
			(at 0 0.762 180)
			(size 0.2159 0.2159)
			(layers "F.Cu" "F.Mask" "F.Paste")
			(net "GND")
			(options
				(clearance outline)
				(anchor circle)
			)
			(primitives
				(gr_poly
					(pts
						(arc
							(start -0.3302 -0.4318)
							(mid -0.402042 -0.402042)
							(end -0.4318 -0.3302)
						)
						(arc
							(start -0.4318 0.3302)
							(mid -0.402042 0.402042)
							(end -0.3302 0.4318)
						)
						(arc
							(start 0.3302 0.4318)
							(mid 0.402042 0.402042)
							(end 0.4318 0.3302)
						)
						(arc
							(start 0.4318 -0.3302)
							(mid 0.402042 -0.402042)
							(end 0.3302 -0.4318)
						)
					)
					(width 0)
					(fill yes)
				)
			)
		)
	)
	(footprint ""
		(layer "F.Cu")
		(at 85.725 -304.6857 180)
		(property "Reference" "R9964"
			(at 0 0 180)
			(layer "F.SilkS")
			(hide yes)
			(effects
				(font
					(size 1.27 1.27)
				)
			)
		)
		(property "Value" "100R1F-GP"
			(at -3.3274 -1.3335 180)
			(unlocked yes)
			(layer "F.Fab")
			(hide yes)
			(effects
				(font
					(size 1.016 1.016)
					(thickness 0.1524)
				)
			)
		)
		(property "Device Type" "R0201H12"
			(at -3.3274 -2.8575 180)
			(unlocked yes)
			(layer "F.Fab")
			(hide yes)
			(effects
				(font
					(size 1.016 1.016)
					(thickness 0.1524)
				)
			)
		)
		(duplicate_pad_numbers_are_jumpers no)
		(fp_rect
			(start -0.2794 0.6477)
			(end 0.2794 -0.6477)
			(stroke
				(width 0)
				(type default)
			)
			(fill no)
			(layer "F.CrtYd")
		)
		(fp_rect
			(start -0.2794 0.6477)
			(end 0.2794 -0.6477)
			(stroke
				(width 0)
				(type default)
			)
			(fill no)
			(layer "F.Fab")
		)
		(pad "1" smd custom
			(at 0 -0.2794 180)
			(size 0.0762 0.0762)
			(layers "F.Cu" "F.Mask" "F.Paste")
			(net "PE_100M_CLK3_N")
			(options
				(clearance outline)
				(anchor circle)
			)
			(primitives
				(gr_poly
					(pts
						(arc
							(start 0.1524 -0.127)
							(mid 0.137521 -0.162921)
							(end 0.1016 -0.1778)
						)
						(arc
							(start -0.1016 -0.1778)
							(mid -0.137521 -0.162921)
							(end -0.1524 -0.127)
						)
						(arc
							(start -0.1524 0.127)
							(mid -0.137521 0.162921)
							(end -0.1016 0.1778)
						)
						(arc
							(start 0.1016 0.1778)
							(mid 0.137521 0.162921)
							(end 0.1524 0.127)
						)
					)
					(width 0)
					(fill yes)
				)
			)
		)
		(pad "2" smd custom
			(at 0 0.2794 180)
			(size 0.0762 0.0762)
			(layers "F.Cu" "F.Mask" "F.Paste")
			(net "PE_100M_CLK3_P")
			(options
				(clearance outline)
				(anchor circle)
			)
			(primitives
				(gr_poly
					(pts
						(arc
							(start 0.1524 -0.127)
							(mid 0.137521 -0.162921)
							(end 0.1016 -0.1778)
						)
						(arc
							(start -0.1016 -0.1778)
							(mid -0.137521 -0.162921)
							(end -0.1524 -0.127)
						)
						(arc
							(start -0.1524 0.127)
							(mid -0.137521 0.162921)
							(end -0.1016 0.1778)
						)
						(arc
							(start 0.1016 0.1778)
							(mid 0.137521 0.162921)
							(end 0.1524 0.127)
						)
					)
					(width 0)
					(fill yes)
				)
			)
		)
	)
	(footprint ""
		(layer "F.Cu")
		(at 24.003 -378.968 90)
		(property "Reference" "R335"
			(at 0 0 90)
			(layer "F.SilkS")
			(hide yes)
			(effects
				(font
					(size 1.27 1.27)
				)
			)
		)
		(property "Value" "0R2J-2-GP"
			(at 0.064008 -3.993896 90)
			(unlocked yes)
			(layer "F.Fab")
			(hide yes)
			(effects
				(font
					(size 1.016 1.016)
					(thickness 0.1524)
				)
			)
		)
		(property "Device Type" "R402H16"
			(at 0.064008 -5.517896 90)
			(unlocked yes)
			(layer "F.Fab")
			(hide yes)
			(effects
				(font
					(size 1.016 1.016)
					(thickness 0.1524)
				)
			)
		)
		(duplicate_pad_numbers_are_jumpers no)
		(fp_line
			(start 0.508 -0.9398)
			(end -0.508 -0.9398)
			(stroke
				(width 0.1524)
				(type default)
			)
			(layer "F.SilkS")
		)
		(fp_line
			(start -0.508 -0.9398)
			(end -0.508 0.9398)
			(stroke
				(width 0.1524)
				(type default)
			)
			(layer "F.SilkS")
		)
		(fp_rect
			(start -0.508 0.9398)
			(end 0.508 -0.9398)
			(stroke
				(width 0)
				(type default)
			)
			(fill no)
			(layer "F.CrtYd")
		)
		(fp_rect
			(start -0.508 0.9398)
			(end 0.508 -0.9398)
			(stroke
				(width 0)
				(type default)
			)
			(fill no)
			(layer "F.Fab")
		)
		(pad "1" smd custom
			(at 0 -0.4445 90)
			(size 0.1397 0.1397)
			(layers "F.Cu" "F.Mask" "F.Paste")
			(net "I2C_B_SCL")
			(options
				(clearance outline)
				(anchor circle)
			)
			(primitives
				(gr_poly
					(pts
						(arc
							(start -0.1778 -0.2794)
							(mid -0.249642 -0.249642)
							(end -0.2794 -0.1778)
						)
						(arc
							(start -0.2794 0.1778)
							(mid -0.249642 0.249642)
							(end -0.1778 0.2794)
						)
						(arc
							(start 0.1778 0.2794)
							(mid 0.249642 0.249642)
							(end 0.2794 0.1778)
						)
						(arc
							(start 0.2794 -0.1778)
							(mid 0.249642 -0.249642)
							(end 0.1778 -0.2794)
						)
					)
					(width 0)
					(fill yes)
				)
			)
		)
		(pad "2" smd custom
			(at 0 0.4445 90)
			(size 0.1397 0.1397)
			(layers "F.Cu" "F.Mask" "F.Paste")
			(net "TMP4_SCL")
			(options
				(clearance outline)
				(anchor circle)
			)
			(primitives
				(gr_poly
					(pts
						(arc
							(start -0.1778 -0.2794)
							(mid -0.249642 -0.249642)
							(end -0.2794 -0.1778)
						)
						(arc
							(start -0.2794 0.1778)
							(mid -0.249642 0.249642)
							(end -0.1778 0.2794)
						)
						(arc
							(start 0.1778 0.2794)
							(mid 0.249642 0.249642)
							(end 0.2794 0.1778)
						)
						(arc
							(start 0.2794 -0.1778)
							(mid 0.249642 -0.249642)
							(end 0.1778 -0.2794)
						)
					)
					(width 0)
					(fill yes)
				)
			)
		)
	)
)
